(kicad_pcb
	(version 20260206)
	(generator "pcbnew")
	(generator_version "10.0")
	(general
		(thickness 1.6)
		(legacy_teardrops no)
	)
	(paper "A4")
	(title_block
		(title "01162023_DA0F0TEBIF0_F0T_Expander_BD_F_brd_V02_OCP.brd")
		(comment 1 "Grand Teton / footprints 995-1002 of 9728")
	)
	(layers
		(0 "F.Cu" signal "TOP")
		(4 "In1.Cu" signal "GND")
		(6 "In2.Cu" signal "VCC")
		(8 "In3.Cu" signal "VCC1")
		(10 "In4.Cu" signal "GND1")
		(12 "In5.Cu" signal "IN1")
		(14 "In6.Cu" signal "GND2")
		(16 "In7.Cu" signal "IN2")
		(18 "In8.Cu" signal "GND3")
		(20 "In9.Cu" signal "IN3")
		(22 "In10.Cu" signal "GND4")
		(24 "In11.Cu" signal "IN4")
		(26 "In12.Cu" signal "GND5")
		(28 "In13.Cu" signal "IN5")
		(30 "In14.Cu" signal "GND6")
		(32 "In15.Cu" signal "IN6")
		(34 "In16.Cu" signal "GND7")
		(2 "B.Cu" signal "BOTTOM")
		(9 "F.Adhes" user "F.Adhesive")
		(11 "B.Adhes" user "B.Adhesive")
		(13 "F.Paste" user "Package Geometry/Pastemask Top")
		(15 "B.Paste" user "Package Geometry/Pastemask Bottom")
		(5 "F.SilkS" user "Ref Des/Silkscreen Top")
		(7 "B.SilkS" user "Ref Des/Silkscreen Bottom")
		(1 "F.Mask" user "Board Geometry/Soldermask Top")
		(3 "B.Mask" user "Board Geometry/Soldermask Bottom")
		(17 "Dwgs.User" user "User.Drawings")
		(19 "Cmts.User" user "User.Comments")
		(21 "Eco1.User" user "User.Eco1")
		(23 "Eco2.User" user "User.Eco2")
		(25 "Edge.Cuts" user "Board Geometry/Outline")
		(27 "Margin" user)
		(31 "F.CrtYd" user "Package Geometry/Place Bound Top")
		(29 "B.CrtYd" user "Package Geometry/Place Bound Bottom")
		(35 "F.Fab" user "Ref Des/Assembly Top")
		(33 "B.Fab" user "Ref Des/Assembly Bottom")
	)
	(footprint ""
		(layer "F.Cu")
		(at 309.81142 -71.458074 -90)
		(property "Reference" "PD109"
			(at 4.351274 -2.71145 90)
			(unlocked yes)
			(layer "F.SilkS")
			(effects
				(font
					(size 0.7874 0.5842)
					(thickness 0.1524)
				)
				(justify left)
			)
		)
		(property "Value" ""
			(at 0 0 270)
			(layer "F.Fab")
			(effects
				(font
					(size 1.27 1.27)
				)
			)
		)
		(duplicate_pad_numbers_are_jumpers no)
		(fp_line
			(start -3.656584 1.970024)
			(end 4.240784 1.970024)
			(stroke
				(width 0.1524)
				(type default)
			)
			(layer "F.SilkS")
		)
		(fp_line
			(start 4.240784 1.970024)
			(end 4.240784 -1.970024)
			(stroke
				(width 0.1524)
				(type default)
			)
			(layer "F.SilkS")
		)
		(fp_line
			(start -3.656584 -1.970024)
			(end -3.656584 1.970024)
			(stroke
				(width 0.1524)
				(type default)
			)
			(layer "F.SilkS")
		)
		(fp_line
			(start 4.240784 -1.970024)
			(end -3.656584 -1.970024)
			(stroke
				(width 0.1524)
				(type default)
			)
			(layer "F.SilkS")
		)
		(fp_poly
			(pts
				(xy 3.580384 1.970024) (xy 3.580384 -1.970024) (xy 4.240784 -1.970024) (xy 4.240784 1.970024)
			)
			(stroke
				(width 0)
				(type default)
			)
			(fill yes)
			(layer "F.SilkS")
		)
		(fp_line
			(start -2.3749 1.970024)
			(end 2.3749 1.970024)
			(stroke
				(width 0.1)
				(type default)
			)
			(layer "F.Fab")
		)
		(fp_line
			(start 2.3749 1.970024)
			(end 2.3749 -1.970024)
			(stroke
				(width 0.1)
				(type default)
			)
			(layer "F.Fab")
		)
		(fp_line
			(start -2.3749 -1.970024)
			(end -2.3749 1.970024)
			(stroke
				(width 0.1)
				(type default)
			)
			(layer "F.Fab")
		)
		(fp_line
			(start 2.3749 -1.970024)
			(end -2.3749 -1.970024)
			(stroke
				(width 0.1)
				(type default)
			)
			(layer "F.Fab")
		)
		(fp_text user "+"
			(at -4.9784 -0.23495 270)
			(unlocked yes)
			(layer "F.Fab")
			(effects
				(font
					(size 1.905 1.4224)
					(thickness 0.1524)
				)
				(justify left)
			)
		)
		(fp_text user "-"
			(at 4.1656 -0.23495 270)
			(unlocked yes)
			(layer "F.Fab")
			(effects
				(font
					(size 1.905 1.4224)
					(thickness 0.1524)
				)
				(justify left)
			)
		)
		(pad "A" smd rect
			(at -2.450084 0 270)
			(size 2.159 2.2606)
			(layers "F.Cu" "F.Mask" "F.Paste")
			(net "GND")
		)
		(pad "C" smd rect
			(at 2.450084 0 270)
			(size 2.159 2.2606)
			(layers "F.Cu" "F.Mask" "F.Paste")
			(net "P12V_AUX")
		)
	)
	(footprint ""
		(layer "F.Cu")
		(at 352.232214 -142.494)
		(property "Reference" "R4839"
			(at 0 0 0)
			(layer "F.SilkS")
			(hide yes)
			(effects
				(font
					(size 1.27 1.27)
				)
			)
		)
		(property "Value" ""
			(at 0 0 0)
			(layer "F.Fab")
			(effects
				(font
					(size 1.27 1.27)
				)
			)
		)
		(duplicate_pad_numbers_are_jumpers no)
		(fp_line
			(start -0.7874 -0.4064)
			(end 0.7874 -0.4064)
			(stroke
				(width 0.1524)
				(type default)
			)
			(layer "F.SilkS")
		)
		(fp_line
			(start -0.7874 0.4064)
			(end -0.7874 -0.4064)
			(stroke
				(width 0.1524)
				(type default)
			)
			(layer "F.SilkS")
		)
		(fp_line
			(start 0.7874 -0.4064)
			(end 0.7874 0.4064)
			(stroke
				(width 0.1524)
				(type default)
			)
			(layer "F.SilkS")
		)
		(fp_line
			(start 0.7874 0.4064)
			(end -0.7874 0.4064)
			(stroke
				(width 0.1524)
				(type default)
			)
			(layer "F.SilkS")
		)
		(fp_line
			(start -0.67945 -0.305054)
			(end -0.12065 -0.305054)
			(stroke
				(width 0.1)
				(type default)
			)
			(layer "F.Fab")
		)
		(fp_line
			(start -0.67945 0.3048)
			(end -0.67945 -0.305054)
			(stroke
				(width 0.1)
				(type default)
			)
			(layer "F.Fab")
		)
		(fp_line
			(start -0.12065 -0.305054)
			(end -0.12065 -0.2794)
			(stroke
				(width 0.1)
				(type default)
			)
			(layer "F.Fab")
		)
		(fp_line
			(start -0.12065 -0.2794)
			(end 0.12065 -0.2794)
			(stroke
				(width 0.1)
				(type default)
			)
			(layer "F.Fab")
		)
		(fp_line
			(start -0.12065 0.2794)
			(end -0.12065 0.3048)
			(stroke
				(width 0.1)
				(type default)
			)
			(layer "F.Fab")
		)
		(fp_line
			(start -0.12065 0.3048)
			(end -0.67945 0.3048)
			(stroke
				(width 0.1)
				(type default)
			)
			(layer "F.Fab")
		)
		(fp_line
			(start 0.120396 0.2794)
			(end -0.12065 0.2794)
			(stroke
				(width 0.1)
				(type default)
			)
			(layer "F.Fab")
		)
		(fp_line
			(start 0.120396 0.3048)
			(end 0.120396 0.2794)
			(stroke
				(width 0.1)
				(type default)
			)
			(layer "F.Fab")
		)
		(fp_line
			(start 0.12065 -0.3048)
			(end 0.67945 -0.3048)
			(stroke
				(width 0.1)
				(type default)
			)
			(layer "F.Fab")
		)
		(fp_line
			(start 0.12065 -0.2794)
			(end 0.12065 -0.3048)
			(stroke
				(width 0.1)
				(type default)
			)
			(layer "F.Fab")
		)
		(fp_line
			(start 0.67945 -0.3048)
			(end 0.67945 0.3048)
			(stroke
				(width 0.1)
				(type default)
			)
			(layer "F.Fab")
		)
		(fp_line
			(start 0.67945 0.3048)
			(end 0.120396 0.3048)
			(stroke
				(width 0.1)
				(type default)
			)
			(layer "F.Fab")
		)
		(pad "1" smd circle
			(at -0.40005 0)
			(size 0 0)
			(layers "F.Cu" "F.Mask" "F.Paste")
			(net "PRSNT_NIC7_FPGA_PCA9555_N")
		)
		(pad "2" smd circle
			(at 0.40005 0)
			(size 0 0)
			(layers "F.Cu" "F.Mask" "F.Paste")
			(net "PRSNT_NIC7_FPGA_R_N")
		)
	)
	(footprint ""
		(layer "F.Cu")
		(at 196.595238 -35.48253)
		(property "Reference" "U388"
			(at -2.588768 0.78613 90)
			(unlocked yes)
			(layer "F.SilkS")
			(effects
				(font
					(size 0.7874 0.5842)
					(thickness 0.1524)
				)
				(justify left)
			)
		)
		(property "Value" ""
			(at 0 0 0)
			(layer "F.Fab")
			(effects
				(font
					(size 1.27 1.27)
				)
			)
		)
		(duplicate_pad_numbers_are_jumpers no)
		(fp_line
			(start -1.3462 -1.1938)
			(end -1.3462 1.1684)
			(stroke
				(width 0.1524)
				(type default)
			)
			(layer "F.SilkS")
		)
		(fp_line
			(start -1.3462 1.1938)
			(end 1.3462 1.1938)
			(stroke
				(width 0.1524)
				(type default)
			)
			(layer "F.SilkS")
		)
		(fp_line
			(start 1.3462 -1.1938)
			(end -1.3462 -1.1938)
			(stroke
				(width 0.1524)
				(type default)
			)
			(layer "F.SilkS")
		)
		(fp_line
			(start 1.3462 1.1938)
			(end 1.3462 -1.1938)
			(stroke
				(width 0.1524)
				(type default)
			)
			(layer "F.SilkS")
		)
		(fp_poly
			(pts
				(xy -1.447038 -0.760476) (xy -2.052066 -0.457962) (xy -2.052066 -1.06299)
			)
			(stroke
				(width 0)
				(type default)
			)
			(fill yes)
			(layer "F.SilkS")
		)
		(fp_line
			(start -0.674878 -1.124966)
			(end -0.674878 1.124966)
			(stroke
				(width 0.1)
				(type default)
			)
			(layer "F.Fab")
		)
		(fp_line
			(start -0.674878 1.124966)
			(end 0.674878 1.124966)
			(stroke
				(width 0.1)
				(type default)
			)
			(layer "F.Fab")
		)
		(fp_line
			(start 0.674878 -1.124966)
			(end -0.674878 -1.124966)
			(stroke
				(width 0.1)
				(type default)
			)
			(layer "F.Fab")
		)
		(fp_line
			(start 0.674878 1.124966)
			(end 0.674878 -1.124966)
			(stroke
				(width 0.1)
				(type default)
			)
			(layer "F.Fab")
		)
		(fp_poly
			(pts
				(xy -1.447038 -0.760476) (xy -2.052066 -0.457962) (xy -2.052066 -1.06299)
			)
			(stroke
				(width 0)
				(type default)
			)
			(fill yes)
			(layer "F.Fab")
		)
		(pad "1" smd rect
			(at -0.899922 -0.750062)
			(size 0.6096 0.6096)
			(layers "F.Cu" "F.Mask" "F.Paste")
			(net "PWRGD_P3V3_SSD7_R")
		)
		(pad "2" smd rect
			(at -0.899922 0 90)
			(size 0.4064 0.6096)
			(layers "F.Cu" "F.Mask" "F.Paste")
			(net "RST_SMB_SSD7_N")
		)
		(pad "3" smd rect
			(at -0.899922 0.750062)
			(size 0.6096 0.6096)
			(layers "F.Cu" "F.Mask" "F.Paste")
			(net "GND")
		)
		(pad "4" smd rect
			(at 0.899922 0.750062)
			(size 0.6096 0.6096)
			(layers "F.Cu" "F.Mask" "F.Paste")
			(net "RST_SMB_SSD7_ISO_N")
		)
		(pad "5" smd rect
			(at 0.899922 -0.750062)
			(size 0.6096 0.6096)
			(layers "F.Cu" "F.Mask" "F.Paste")
			(net "P3V3_AUX")
		)
	)
	(footprint ""
		(layer "F.Cu")
		(at 117.700298 -72.700134)
		(property "Reference" "H49"
			(at -4.721606 -5.20573 0)
			(unlocked yes)
			(layer "F.SilkS")
			(effects
				(font
					(size 0.7874 0.5842)
					(thickness 0.1524)
				)
				(justify left)
			)
		)
		(property "Value" ""
			(at 0 0 0)
			(layer "F.Fab")
			(effects
				(font
					(size 1.27 1.27)
				)
			)
		)
		(duplicate_pad_numbers_are_jumpers no)
		(pad "1" thru_hole circle
			(at 0 0)
			(size 10.0076 10.0076)
			(drill 5.6134)
			(layers "*.Cu" "*.Mask")
			(remove_unused_layers no)
			(net "GND")
			(clearance -1.9431)
		)
	)
	(footprint ""
		(layer "F.Cu")
		(at 220.36786 -52.035456 180)
		(property "Reference" "R868"
			(at 0 0 180)
			(layer "F.SilkS")
			(hide yes)
			(effects
				(font
					(size 1.27 1.27)
				)
			)
		)
		(property "Value" ""
			(at 0 0 180)
			(layer "F.Fab")
			(effects
				(font
					(size 1.27 1.27)
				)
			)
		)
		(duplicate_pad_numbers_are_jumpers no)
		(fp_line
			(start 0.7874 0.4064)
			(end -0.7874 0.4064)
			(stroke
				(width 0.1524)
				(type default)
			)
			(layer "F.SilkS")
		)
		(fp_line
			(start 0.7874 -0.4064)
			(end 0.7874 0.4064)
			(stroke
				(width 0.1524)
				(type default)
			)
			(layer "F.SilkS")
		)
		(fp_line
			(start -0.7874 0.4064)
			(end -0.7874 -0.4064)
			(stroke
				(width 0.1524)
				(type default)
			)
			(layer "F.SilkS")
		)
		(fp_line
			(start -0.7874 -0.4064)
			(end 0.7874 -0.4064)
			(stroke
				(width 0.1524)
				(type default)
			)
			(layer "F.SilkS")
		)
		(fp_line
			(start 0.67945 0.3048)
			(end 0.120396 0.3048)
			(stroke
				(width 0.1)
				(type default)
			)
			(layer "F.Fab")
		)
		(fp_line
			(start 0.67945 -0.3048)
			(end 0.67945 0.3048)
			(stroke
				(width 0.1)
				(type default)
			)
			(layer "F.Fab")
		)
		(fp_line
			(start 0.12065 -0.2794)
			(end 0.12065 -0.3048)
			(stroke
				(width 0.1)
				(type default)
			)
			(layer "F.Fab")
		)
		(fp_line
			(start 0.12065 -0.3048)
			(end 0.67945 -0.3048)
			(stroke
				(width 0.1)
				(type default)
			)
			(layer "F.Fab")
		)
		(fp_line
			(start 0.120396 0.3048)
			(end 0.120396 0.2794)
			(stroke
				(width 0.1)
				(type default)
			)
			(layer "F.Fab")
		)
		(fp_line
			(start 0.120396 0.2794)
			(end -0.12065 0.2794)
			(stroke
				(width 0.1)
				(type default)
			)
			(layer "F.Fab")
		)
		(fp_line
			(start -0.12065 0.3048)
			(end -0.67945 0.3048)
			(stroke
				(width 0.1)
				(type default)
			)
			(layer "F.Fab")
		)
		(fp_line
			(start -0.12065 0.2794)
			(end -0.12065 0.3048)
			(stroke
				(width 0.1)
				(type default)
			)
			(layer "F.Fab")
		)
		(fp_line
			(start -0.12065 -0.2794)
			(end 0.12065 -0.2794)
			(stroke
				(width 0.1)
				(type default)
			)
			(layer "F.Fab")
		)
		(fp_line
			(start -0.12065 -0.305054)
			(end -0.12065 -0.2794)
			(stroke
				(width 0.1)
				(type default)
			)
			(layer "F.Fab")
		)
		(fp_line
			(start -0.67945 0.3048)
			(end -0.67945 -0.305054)
			(stroke
				(width 0.1)
				(type default)
			)
			(layer "F.Fab")
		)
		(fp_line
			(start -0.67945 -0.305054)
			(end -0.12065 -0.305054)
			(stroke
				(width 0.1)
				(type default)
			)
			(layer "F.Fab")
		)
		(pad "1" smd circle
			(at -0.40005 0 180)
			(size 0 0)
			(layers "F.Cu" "F.Mask" "F.Paste")
			(net "P3V3_AUX")
		)
		(pad "2" smd circle
			(at 0.40005 0 180)
			(size 0 0)
			(layers "F.Cu" "F.Mask" "F.Paste")
			(net "PWRGD_P12V_SSD7")
		)
	)
	(footprint ""
		(layer "F.Cu")
		(at 418.596572 -343.952322 90)
		(property "Reference" "C2447"
			(at 0 0 90)
			(layer "F.SilkS")
			(hide yes)
			(effects
				(font
					(size 1.27 1.27)
				)
			)
		)
		(property "Value" ""
			(at 0 0 90)
			(layer "F.Fab")
			(effects
				(font
					(size 1.27 1.27)
				)
			)
		)
		(duplicate_pad_numbers_are_jumpers no)
		(fp_line
			(start 0.299974 -0.150114)
			(end 0.299974 0.150114)
			(stroke
				(width 0.1)
				(type default)
			)
			(layer "F.Fab")
		)
		(fp_line
			(start -0.299974 -0.150114)
			(end 0.299974 -0.150114)
			(stroke
				(width 0.1)
				(type default)
			)
			(layer "F.Fab")
		)
		(fp_line
			(start 0.299974 0.150114)
			(end -0.299974 0.150114)
			(stroke
				(width 0.1)
				(type default)
			)
			(layer "F.Fab")
		)
		(fp_line
			(start -0.299974 0.150114)
			(end -0.299974 -0.150114)
			(stroke
				(width 0.1)
				(type default)
			)
			(layer "F.Fab")
		)
		(pad "1" smd rect
			(at -0.2667 0 90)
			(size 0.3048 0.381)
			(layers "F.Cu" "F.Mask" "F.Paste")
			(net "P5E_PEX3_STN4_TX_DP<75>")
		)
		(pad "2" smd rect
			(at 0.2667 0 90)
			(size 0.3048 0.381)
			(layers "F.Cu" "F.Mask" "F.Paste")
			(net "P5E_PEX3_STN4_TX_C_DP<75>")
		)
	)
	(footprint ""
		(layer "F.Cu")
		(at 58.686192 -387.750812)
		(property "Reference" "R1829"
			(at 0 0 0)
			(layer "F.SilkS")
			(hide yes)
			(effects
				(font
					(size 1.27 1.27)
				)
			)
		)
		(property "Value" ""
			(at 0 0 0)
			(layer "F.Fab")
			(effects
				(font
					(size 1.27 1.27)
				)
			)
		)
		(duplicate_pad_numbers_are_jumpers no)
		(fp_line
			(start -0.7874 -0.4064)
			(end 0.7874 -0.4064)
			(stroke
				(width 0.1524)
				(type default)
			)
			(layer "F.SilkS")
		)
		(fp_line
			(start -0.7874 0.4064)
			(end -0.7874 -0.4064)
			(stroke
				(width 0.1524)
				(type default)
			)
			(layer "F.SilkS")
		)
		(fp_line
			(start 0.7874 -0.4064)
			(end 0.7874 0.4064)
			(stroke
				(width 0.1524)
				(type default)
			)
			(layer "F.SilkS")
		)
		(fp_line
			(start 0.7874 0.4064)
			(end -0.7874 0.4064)
			(stroke
				(width 0.1524)
				(type default)
			)
			(layer "F.SilkS")
		)
		(fp_line
			(start -0.67945 -0.305054)
			(end -0.12065 -0.305054)
			(stroke
				(width 0.1)
				(type default)
			)
			(layer "F.Fab")
		)
		(fp_line
			(start -0.67945 0.3048)
			(end -0.67945 -0.305054)
			(stroke
				(width 0.1)
				(type default)
			)
			(layer "F.Fab")
		)
		(fp_line
			(start -0.12065 -0.305054)
			(end -0.12065 -0.2794)
			(stroke
				(width 0.1)
				(type default)
			)
			(layer "F.Fab")
		)
		(fp_line
			(start -0.12065 -0.2794)
			(end 0.12065 -0.2794)
			(stroke
				(width 0.1)
				(type default)
			)
			(layer "F.Fab")
		)
		(fp_line
			(start -0.12065 0.2794)
			(end -0.12065 0.3048)
			(stroke
				(width 0.1)
				(type default)
			)
			(layer "F.Fab")
		)
		(fp_line
			(start -0.12065 0.3048)
			(end -0.67945 0.3048)
			(stroke
				(width 0.1)
				(type default)
			)
			(layer "F.Fab")
		)
		(fp_line
			(start 0.120396 0.2794)
			(end -0.12065 0.2794)
			(stroke
				(width 0.1)
				(type default)
			)
			(layer "F.Fab")
		)
		(fp_line
			(start 0.120396 0.3048)
			(end 0.120396 0.2794)
			(stroke
				(width 0.1)
				(type default)
			)
			(layer "F.Fab")
		)
		(fp_line
			(start 0.12065 -0.3048)
			(end 0.67945 -0.3048)
			(stroke
				(width 0.1)
				(type default)
			)
			(layer "F.Fab")
		)
		(fp_line
			(start 0.12065 -0.2794)
			(end 0.12065 -0.3048)
			(stroke
				(width 0.1)
				(type default)
			)
			(layer "F.Fab")
		)
		(fp_line
			(start 0.67945 -0.3048)
			(end 0.67945 0.3048)
			(stroke
				(width 0.1)
				(type default)
			)
			(layer "F.Fab")
		)
		(fp_line
			(start 0.67945 0.3048)
			(end 0.120396 0.3048)
			(stroke
				(width 0.1)
				(type default)
			)
			(layer "F.Fab")
		)
		(pad "1" smd circle
			(at -0.40005 0)
			(size 0 0)
			(layers "F.Cu" "F.Mask" "F.Paste")
			(net "GPU_PWR_BRAKE_R_N")
		)
		(pad "2" smd circle
			(at 0.40005 0)
			(size 0 0)
			(layers "F.Cu" "F.Mask" "F.Paste")
			(net "GPU_PWR_BRAKE_N")
		)
	)
	(footprint ""
		(layer "F.Cu")
		(at 334.227932 -275.813774 180)
		(property "Reference" "PC6617"
			(at 0 0 180)
			(layer "F.SilkS")
			(hide yes)
			(effects
				(font
					(size 1.27 1.27)
				)
			)
		)
		(property "Value" ""
			(at 0 0 180)
			(layer "F.Fab")
			(effects
				(font
					(size 1.27 1.27)
				)
			)
		)
		(duplicate_pad_numbers_are_jumpers no)
		(fp_line
			(start 1.524 0.762)
			(end -1.524 0.762)
			(stroke
				(width 0.1524)
				(type default)
			)
			(layer "F.SilkS")
		)
		(fp_line
			(start 1.524 -0.762)
			(end 1.524 0.762)
			(stroke
				(width 0.1524)
				(type default)
			)
			(layer "F.SilkS")
		)
		(fp_line
			(start -1.524 0.762)
			(end -1.524 -0.762)
			(stroke
				(width 0.1524)
				(type default)
			)
			(layer "F.SilkS")
		)
		(fp_line
			(start -1.524 -0.762)
			(end 1.524 -0.762)
			(stroke
				(width 0.1524)
				(type default)
			)
			(layer "F.SilkS")
		)
		(fp_line
			(start 1.1049 0.724916)
			(end 1.1049 -0.724916)
			(stroke
				(width 0.1)
				(type default)
			)
			(layer "F.Fab")
		)
		(fp_line
			(start 1.1049 -0.724916)
			(end -1.1049 -0.724916)
			(stroke
				(width 0.1)
				(type default)
			)
			(layer "F.Fab")
		)
		(fp_line
			(start -1.1049 0.724916)
			(end 1.1049 0.724916)
			(stroke
				(width 0.1)
				(type default)
			)
			(layer "F.Fab")
		)
		(fp_line
			(start -1.1049 -0.724916)
			(end -1.1049 0.724916)
			(stroke
				(width 0.1)
				(type default)
			)
			(layer "F.Fab")
		)
		(pad "1" smd rect
			(at -0.889 0)
			(size 1.016 1.27)
			(layers "F.Cu" "F.Mask" "F.Paste")
			(net "SW_P12V_P0V8_PEX2_FLT")
		)
		(pad "2" smd rect
			(at 0.889 0)
			(size 1.016 1.27)
			(layers "F.Cu" "F.Mask" "F.Paste")
			(net "GND")
		)
	)
)
